# S9S_MB_2U (Grand Teton) — schematic netlist excerpt (pin names and nets, part order shuffled) for the footprints in the layout excerpt that follows; sources: Cadence DE-HDL packaged netlist, KiCad conversion of 03242023_DA0F0TMBIJ0_F0T_Motherboard_J_brd_V01_OCP.brd

J12  SCONN288_ADR50017P087CC  SCONN288_ADR50017-P087CC IO  pkg DDR288S_1-1VXB  page 93
  VIN_BULK0  = P12V_S3_AUX_CPU0_NVDIMM
  RFU0  = TP_CHF_CPU0_DIMM2_FRU_0
  VIN_MGMT  = P3V3_AUX
  HSCL  = I3C_SPD_DDREFGH_CPU0_LVC1_SCL_3
  HSDA  = I3C_SPD_DDREFGH_CPU0_LVC1_SDA
  VSS0  = GND
  DQ0_A  = M_F_CPU0_SA_DQ<0>
  VSS1  = GND
  DQ1_A  = M_F_CPU0_SA_DQ<1>
  VSS2  = GND
  DQS0_A_T  = M_F_CPU0_SA_DQS_DP<0>
  DQS0_A_C  = M_F_CPU0_SA_DQS_DN<0>
  VSS3  = GND
  DQ4_A  = M_F_CPU0_SA_DQ<4>
  VSS4  = GND
  DQ5_A  = M_F_CPU0_SA_DQ<5>
  VSS5  = GND
  DQ8_A  = M_F_CPU0_SA_DQ<8>
  VSS6  = GND
  DQ9_A  = M_F_CPU0_SA_DQ<9>
  VSS7  = GND
  DQS1_A_T  = M_F_CPU0_SA_DQS_DP<1>
  DQS1_A_C  = M_F_CPU0_SA_DQS_DN<1>
  VSS8  = GND
  DQ12_A  = M_F_CPU0_SA_DQ<12>
  VSS9  = GND
  DQ13_A  = M_F_CPU0_SA_DQ<13>
  VSS10  = GND
  DQ16_A  = M_F_CPU0_SA_DQ<16>
  VSS11  = GND
  DQ17_A  = M_F_CPU0_SA_DQ<17>
  VSS12  = GND
  DQS2_A_T  = M_F_CPU0_SA_DQS_DP<2>
  DQS2_A_C  = M_F_CPU0_SA_DQS_DN<2>
  VSS13  = GND
  DQ20_A  = M_F_CPU0_SA_DQ<20>
  VSS14  = GND
  DQ21_A  = M_F_CPU0_SA_DQ<21>
  VSS15  = GND
  DQ24_A  = M_F_CPU0_SA_DQ<24>
  VSS16  = GND
  DQ25_A  = M_F_CPU0_SA_DQ<25>
  VSS17  = GND
  DQS3_A_T  = M_F_CPU0_SA_DQS_DP<3>
  DQS3_A_C  = M_F_CPU0_SA_DQS_DN<3>
  VSS18  = GND
  DQ28_A  = M_F_CPU0_SA_DQ<28>
  VSS19  = GND
  DQ29_A  = M_F_CPU0_SA_DQ<29>
  VSS20  = GND
  CB0_A  = M_F_CPU0_SA_CB<0>
  VSS21  = GND
  CB1_A  = M_F_CPU0_SA_CB<1>
  VSS22  = GND
  DQS4_A_T  = M_F_CPU0_SA_DQS_DP<4>
  DQS4_A_C  = M_F_CPU0_SA_DQS_DN<4>
  VSS23  = GND
  CB4_A  = M_F_CPU0_SA_CB<4>
  VSS24  = GND
  CB5_A  = M_F_CPU0_SA_CB<5>
  VSS25  = GND
  ALERT_N  = M_F_CPU0_ALERT_N
  VSS26  = GND
  CS0_A_N  = M_F_CPU0_SA_CS_N<2>
  VSS27  = GND
  CA0_A  = M_F_CPU0_SA_CA<0>
  VSS28  = GND
  CA2_A  = M_F_CPU0_SA_CA<2>
  VSS29  = GND
  CA4_A  = M_F_CPU0_SA_CA<4>
  VSS30  = GND
  CA6_A  = M_F_CPU0_SA_CA<6>
  VSS31  = GND
  PAR_A  = M_F_CPU0_SA_PAR
  VSS32  = GND
  CA0_B  = M_F_CPU0_SB_CA<0>
  VSS33  = GND
  CA2_B  = M_F_CPU0_SB_CA<2>
  VSS34  = GND
  CA4_B  = M_F_CPU0_SB_CA<4>
  VSS35  = GND
  CA6_B  = M_F_CPU0_SB_CA<6>
  VSS36  = GND
  CS0_B_N  = M_F_CPU0_SB_CS_N<2>
  VSS37  = GND
  \lbd||rsp_a_n\  = M_F_CPU0_SA_RSP<1>
  \lbs||rsp_b_n\  = M_F_CPU0_SB_RSP<1>
  VSS38  = GND
  CB4_B  = M_F_CPU0_SB_CB<4>
  VSS39  = GND
  CB5_B  = M_F_CPU0_SB_CB<5>
  VSS40  = GND
  \dqs9_b_t||tdqs9_b_t||dbi4_b_n\  = M_F_CPU0_SB_DQS_DP<9>
  \dqs9_b_c||tdqs9_b_c\  = M_F_CPU0_SB_DQS_DN<9>
  VSS41  = GND
  CB0_B  = M_F_CPU0_SB_CB<0>
  VSS42  = GND
  CB1_B  = M_F_CPU0_SB_CB<1>
  VSS43  = GND
  DQ0_B  = M_F_CPU0_SB_DQ<0>
  VSS44  = GND
  DQ1_B  = M_F_CPU0_SB_DQ<1>
  VSS45  = GND
  DQS0_B_T  = M_F_CPU0_SB_DQS_DP<0>
  DQS0_B_C  = M_F_CPU0_SB_DQS_DN<0>
  VSS46  = GND
  DQ4_B  = M_F_CPU0_SB_DQ<4>
  VSS47  = GND
  DQ5_B  = M_F_CPU0_SB_DQ<5>
  VSS48  = GND
  DQ8_B  = M_F_CPU0_SB_DQ<8>
  VSS49  = GND
  DQ9_B  = M_F_CPU0_SB_DQ<9>
  VSS50  = GND
  DQS1_B_T  = M_F_CPU0_SB_DQS_DP<1>
  DQS1_B_C  = M_F_CPU0_SB_DQS_DN<1>
  VSS51  = GND
  DQ12_B  = M_F_CPU0_SB_DQ<12>
  VSS52  = GND
  DQ13_B  = M_F_CPU0_SB_DQ<13>
  VSS53  = GND
  DQ16_B  = M_F_CPU0_SB_DQ<16>
  VSS54  = GND
  DQ17_B  = M_F_CPU0_SB_DQ<17>
  VSS55  = GND
  DQS2_B_T  = M_F_CPU0_SB_DQS_DP<2>
  DQS2_B_C  = M_F_CPU0_SB_DQS_DN<2>
  VSS56  = GND
  DQ20_B  = M_F_CPU0_SB_DQ<20>
  VSS57  = GND
  DQ21_B  = M_F_CPU0_SB_DQ<21>
  VSS58  = GND
  DQ24_B  = M_F_CPU0_SB_DQ<24>
  VSS59  = GND
  DQ25_B  = M_F_CPU0_SB_DQ<25>
  VSS60  = GND
  DQS3_B_T  = M_F_CPU0_SB_DQS_DP<3>
  DQS3_B_C  = M_F_CPU0_SB_DQS_DN<3>
  VSS61  = GND
  DQ28_B  = M_F_CPU0_SB_DQ<28>
  VSS62  = GND
  DQ29_B  = M_F_CPU0_SB_DQ<29>
  VSS63  = GND
  RFU1  = TP_CHF_CPU0_DIMM2_FRU_1
  VIN_BULK1  = P12V_S3_AUX_CPU0_NVDIMM
  VIN_BULK2  = P12V_S3_AUX_CPU0_NVDIMM
  \pwr_good||fail_n\  = PWRGD_CHF_CPU0_DIMM2
  HSA  = PD_CHF_CPU0_DIMM2_SAA
  RFU2  = TP_CHF_CPU0_DIMM2_FRU_2
  RFU3  = TP_CHF_CPU0_DIMM2_FRU_3
  VSS64  = GND
  DQ2_A  = M_F_CPU0_SA_DQ<2>
  VSS65  = GND
  DQ3_A  = M_F_CPU0_SA_DQ<3>
  VSS66  = GND
  \dqs5_a_c||tdqs5_a_c||dqs5_a_t||tdqs5_a_t\  = M_F_CPU0_SA_DQS_DN<5>
  \dqs5_a_t||tdqs5_a_t\  = M_F_CPU0_SA_DQS_DP<5>
  VSS67  = GND
  DQ6_A  = M_F_CPU0_SA_DQ<6>
  VSS68  = GND
  DQ7_A  = M_F_CPU0_SA_DQ<7>
  VSS69  = GND
  DQ10_A  = M_F_CPU0_SA_DQ<10>
  VSS70  = GND
  DQ11_A  = M_F_CPU0_SA_DQ<11>
  VSS71  = GND
  \dqs6_a_c||tdqs6_a_c||dqs6_a_t||tdqs6_a_t\  = M_F_CPU0_SA_DQS_DN<6>
  \dqs6_a_t||tdqs6_a_t\  = M_F_CPU0_SA_DQS_DP<6>
  VSS72  = GND
  DQ14_A  = M_F_CPU0_SA_DQ<14>
  VSS73  = GND
  DQ15_A  = M_F_CPU0_SA_DQ<15>
  VSS74  = GND
  DQ18_A  = M_F_CPU0_SA_DQ<18>
  VSS75  = GND
  DQ19_A  = M_F_CPU0_SA_DQ<19>
  VSS76  = GND
  \dqs7_a_c||tdqs7_a_c\  = M_F_CPU0_SA_DQS_DN<7>
  \dqs7_a_t||tdqs7_a_t\  = M_F_CPU0_SA_DQS_DP<7>
  VSS77  = GND
  DQ22_A  = M_F_CPU0_SA_DQ<22>
  VSS78  = GND
  DQ23_A  = M_F_CPU0_SA_DQ<23>
  VSS79  = GND
  DQ26_A  = M_F_CPU0_SA_DQ<26>
  VSS80  = GND
  DQ27_A  = M_F_CPU0_SA_DQ<27>
  VSS81  = GND
  \dqs8_a_c||tdqs8_a_c\  = M_F_CPU0_SA_DQS_DN<8>
  \dqs8_a_t||tdqs8_a_t\  = M_F_CPU0_SA_DQS_DP<8>
  VSS82  = GND
  DQ30_A  = M_F_CPU0_SA_DQ<30>
  VSS83  = GND
  DQ31_A  = M_F_CPU0_SA_DQ<31>
  VSS84  = GND
  CB2_A  = M_F_CPU0_SA_CB<2>
  VSS85  = GND
  CB3_A  = M_F_CPU0_SA_CB<3>
  VSS86  = GND
  \dqs9_a_c||tdqs9_a_c\  = M_F_CPU0_SA_DQS_DN<9>
  \dqs9_a_t||tdqs9_a_t\  = M_F_CPU0_SA_DQS_DP<9>
  VSS87  = GND
  CB6_A  = M_F_CPU0_SA_CB<6>
  VSS88  = GND
  CB7_A  = M_F_CPU0_SA_CB<7>
  VSS89  = GND
  RESET_N  = RST_M_EF_CPU0_FPGA_N
  VSS90  = GND
  CS1_A_N  = M_F_CPU0_SA_CS_N<3>
  VSS91  = GND
  CA1_A  = M_F_CPU0_SA_CA<1>
  VSS92  = GND
  CA3_A  = M_F_CPU0_SA_CA<3>
  VSS93  = GND
  CA5_A  = M_F_CPU0_SA_CA<5>
  VSS94  = GND
  CK_T  = M_F_CPU0_CLK_DP<1>
  CK_C  = M_F_CPU0_CLK_DN<1>
  VSS95  = GND
  RFU4  = TP_CHF_CPU0_DIMM2_FRU_4
  CA1_B  = M_F_CPU0_SB_CA<1>
  VSS96  = GND
  CA3_B  = M_F_CPU0_SB_CA<3>
  VSS97  = GND
  CA5_B  = M_F_CPU0_SB_CA<5>
  VSS98  = GND
  PAR_B  = M_F_CPU0_SB_PAR
  VSS99  = GND
  CS1_B_N  = M_F_CPU0_SB_CS_N<3>
  VSS100  = GND
  RFU5  = TP_CHF_CPU0_DIMM2_FRU_5
  RFU6  = TP_CHF_CPU0_DIMM2_FRU_6
  VSS101  = GND
  CB6_B  = M_F_CPU0_SB_CB<6>
  VSS102  = GND
  CB7_B  = M_F_CPU0_SB_CB<7>
  VSS103  = GND
  DQS4_B_C  = M_F_CPU0_SB_DQS_DN<4>
  DQS4_B_T  = M_F_CPU0_SB_DQS_DP<4>
  VSS104  = GND
  CB2_B  = M_F_CPU0_SB_CB<2>
  VSS105  = GND
  CB3_B  = M_F_CPU0_SB_CB<3>
  VSS106  = GND
  DQ2_B  = M_F_CPU0_SB_DQ<2>
  VSS107  = GND
  DQ3_B  = M_F_CPU0_SB_DQ<3>
  VSS108  = GND
  \dqs5_b_c||tdqs5_b_c\  = M_F_CPU0_SB_DQS_DN<5>
  \dqs5_b_t||tdqs5_b_t\  = M_F_CPU0_SB_DQS_DP<5>
  VSS109  = GND
  DQ6_B  = M_F_CPU0_SB_DQ<6>
  VSS110  = GND
  DQ7_B  = M_F_CPU0_SB_DQ<7>
  VSS111  = GND
  DQ10_B  = M_F_CPU0_SB_DQ<10>
  VSS112  = GND
  DQ11_B  = M_F_CPU0_SB_DQ<11>
  VSS113  = GND
  \dqs6_b_c||tdqs6_b_c\  = M_F_CPU0_SB_DQS_DN<6>
  \dqs6_b_t||tdqs6_b_t\  = M_F_CPU0_SB_DQS_DP<6>
  VSS114  = GND
  DQ14_B  = M_F_CPU0_SB_DQ<14>
  VSS115  = GND
  DQ15_B  = M_F_CPU0_SB_DQ<15>
  VSS116  = GND
  DQ18_B  = M_F_CPU0_SB_DQ<18>
  VSS117  = GND
  DQ19_B  = M_F_CPU0_SB_DQ<19>
  VSS118  = GND
  \dqs7_b_c||tdqs7_b_c\  = M_F_CPU0_SB_DQS_DN<7>
  \dqs7_b_t||tdqs7_b_t\  = M_F_CPU0_SB_DQS_DP<7>
  VSS119  = GND
  DQ22_B  = M_F_CPU0_SB_DQ<22>
  VSS120  = GND
  DQ23_B  = M_F_CPU0_SB_DQ<23>
  VSS121  = GND
  DQ26_B  = M_F_CPU0_SB_DQ<26>
  VSS122  = GND
  DQ27_B  = M_F_CPU0_SB_DQ<27>
  VSS123  = GND
  \dqs8_b_c||tdqs8_b_c\  = M_F_CPU0_SB_DQS_DN<8>
  \dqs8_b_t||tdqs8_b_t\  = M_F_CPU0_SB_DQS_DP<8>
  VSS124  = GND
  DQ30_B  = M_F_CPU0_SB_DQ<30>
  VSS125  = GND
  DQ31_B  = M_F_CPU0_SB_DQ<31>
  VSS126  = GND
  G1  = GND
  G2  = GND
  G3  = GND

(kicad_pcb
	(version 20260206)
	(generator "pcbnew")
	(generator_version "10.0")
	(general
		(thickness 1.6)
		(legacy_teardrops no)
	)
	(paper "A4")
	(title_block
		(title "03242023_DA0F0TMBIJ0_F0T_Motherboard_J_brd_V01_OCP.brd")
		(comment 1 "Grand Teton / footprint 3198 of 6105 (J12), pads 46-91 of 291")
	)
	(layers
		(0 "F.Cu" signal "TOP")
		(4 "In1.Cu" signal "GND")
		(6 "In2.Cu" signal "IN1")
		(8 "In3.Cu" signal "GND1")
		(10 "In4.Cu" signal "IN2")
		(12 "In5.Cu" signal "GND2")
		(14 "In6.Cu" signal "IN3")
		(16 "In7.Cu" signal "GND3")
		(18 "In8.Cu" signal "VCC")
		(20 "In9.Cu" signal "VCC1")
		(22 "In10.Cu" signal "GND4")
		(24 "In11.Cu" signal "IN4")
		(26 "In12.Cu" signal "GND5")
		(28 "In13.Cu" signal "IN5")
		(30 "In14.Cu" signal "GND6")
		(32 "In15.Cu" signal "IN6")
		(34 "In16.Cu" signal "GND7")
		(2 "B.Cu" signal "BOTTOM")
		(9 "F.Adhes" user "F.Adhesive")
		(11 "B.Adhes" user "B.Adhesive")
		(13 "F.Paste" user "Package Geometry/Pastemask Top")
		(15 "B.Paste" user "Package Geometry/Pastemask Bottom")
		(5 "F.SilkS" user "Ref Des/Silkscreen Top")
		(7 "B.SilkS" user "Ref Des/Silkscreen Bottom")
		(1 "F.Mask" user "Board Geometry/Soldermask Top")
		(3 "B.Mask" user "Board Geometry/Soldermask Bottom")
		(17 "Dwgs.User" user "User.Drawings")
		(19 "Cmts.User" user "User.Comments")
		(21 "Eco1.User" user "User.Eco1")
		(23 "Eco2.User" user "User.Eco2")
		(25 "Edge.Cuts" user "Board Geometry/Outline")
		(27 "Margin" user)
		(31 "F.CrtYd" user "Package Geometry/Place Bound Top")
		(29 "B.CrtYd" user "Package Geometry/Place Bound Bottom")
		(35 "F.Fab" user "Ref Des/Assembly Top")
		(33 "B.Fab" user "Ref Des/Assembly Bottom")
	)
	(footprint ""
		(layer "F.Cu")
		(at 423.890948 -258.091686)
		(property "Reference" "J12"
			(at -3.683 -81.702148 0)
			(unlocked yes)
			(layer "F.SilkS")
			(effects
				(font
					(size 0.7874 0.5842)
					(thickness 0.1524)
				)
				(justify left)
			)
		)
		(property "Value" ""
			(at 0 0 0)
			(layer "F.Fab")
			(effects
				(font
					(size 1.27 1.27)
				)
			)
		)
		(duplicate_pad_numbers_are_jumpers no)
		(pad "46" smd rect
			(at -2.050034 -25.07488 270)
			(size 0.519938 1.4986)
			(layers "F.Cu" "F.Mask" "F.Paste")
			(net "GND")
		)
		(pad "47" smd rect
			(at -2.050034 -24.224996 270)
			(size 0.519938 1.4986)
			(layers "F.Cu" "F.Mask" "F.Paste")
			(net "M_F_CPU0_SA_DQ<28>")
		)
		(pad "48" smd rect
			(at -2.050034 -23.375112 270)
			(size 0.519938 1.4986)
			(layers "F.Cu" "F.Mask" "F.Paste")
			(net "GND")
		)
		(pad "49" smd rect
			(at -2.050034 -22.524974 270)
			(size 0.519938 1.4986)
			(layers "F.Cu" "F.Mask" "F.Paste")
			(net "M_F_CPU0_SA_DQ<29>")
		)
		(pad "50" smd rect
			(at -2.050034 -21.67509 270)
			(size 0.519938 1.4986)
			(layers "F.Cu" "F.Mask" "F.Paste")
			(net "GND")
		)
		(pad "51" smd rect
			(at -2.050034 -20.824952 270)
			(size 0.519938 1.4986)
			(layers "F.Cu" "F.Mask" "F.Paste")
			(net "M_F_CPU0_SA_CB<0>")
		)
		(pad "52" smd rect
			(at -2.050034 -19.975068 270)
			(size 0.519938 1.4986)
			(layers "F.Cu" "F.Mask" "F.Paste")
			(net "GND")
		)
		(pad "53" smd rect
			(at -2.050034 -19.12493 270)
			(size 0.519938 1.4986)
			(layers "F.Cu" "F.Mask" "F.Paste")
			(net "M_F_CPU0_SA_CB<1>")
		)
		(pad "54" smd rect
			(at -2.050034 -18.275046 270)
			(size 0.519938 1.4986)
			(layers "F.Cu" "F.Mask" "F.Paste")
			(net "GND")
		)
		(pad "55" smd rect
			(at -2.050034 -17.424908 270)
			(size 0.519938 1.4986)
			(layers "F.Cu" "F.Mask" "F.Paste")
			(net "M_F_CPU0_SA_DQS_DP<4>")
		)
		(pad "56" smd rect
			(at -2.050034 -16.575024 270)
			(size 0.519938 1.4986)
			(layers "F.Cu" "F.Mask" "F.Paste")
			(net "M_F_CPU0_SA_DQS_DN<4>")
		)
		(pad "57" smd rect
			(at -2.050034 -15.724886 270)
			(size 0.519938 1.4986)
			(layers "F.Cu" "F.Mask" "F.Paste")
			(net "GND")
		)
		(pad "58" smd rect
			(at -2.050034 -14.875002 270)
			(size 0.519938 1.4986)
			(layers "F.Cu" "F.Mask" "F.Paste")
			(net "M_F_CPU0_SA_CB<4>")
		)
		(pad "59" smd rect
			(at -2.050034 -14.025118 270)
			(size 0.519938 1.4986)
			(layers "F.Cu" "F.Mask" "F.Paste")
			(net "GND")
		)
		(pad "60" smd rect
			(at -2.050034 -13.17498 270)
			(size 0.519938 1.4986)
			(layers "F.Cu" "F.Mask" "F.Paste")
			(net "M_F_CPU0_SA_CB<5>")
		)
		(pad "61" smd rect
			(at -2.050034 -12.325096 270)
			(size 0.519938 1.4986)
			(layers "F.Cu" "F.Mask" "F.Paste")
			(net "GND")
		)
		(pad "62" smd rect
			(at -2.050034 -11.474958 270)
			(size 0.519938 1.4986)
			(layers "F.Cu" "F.Mask" "F.Paste")
			(net "M_F_CPU0_ALERT_N")
		)
		(pad "63" smd rect
			(at -2.050034 -10.625074 270)
			(size 0.519938 1.4986)
			(layers "F.Cu" "F.Mask" "F.Paste")
			(net "GND")
		)
		(pad "64" smd rect
			(at -2.050034 -9.774936 270)
			(size 0.519938 1.4986)
			(layers "F.Cu" "F.Mask" "F.Paste")
			(net "M_F_CPU0_SA_CS_N<2>")
		)
		(pad "65" smd rect
			(at -2.050034 -8.925052 270)
			(size 0.519938 1.4986)
			(layers "F.Cu" "F.Mask" "F.Paste")
			(net "GND")
		)
		(pad "66" smd rect
			(at -2.050034 -8.074914 270)
			(size 0.519938 1.4986)
			(layers "F.Cu" "F.Mask" "F.Paste")
			(net "M_F_CPU0_SA_CA<0>")
		)
		(pad "67" smd rect
			(at -2.050034 -7.22503 270)
			(size 0.519938 1.4986)
			(layers "F.Cu" "F.Mask" "F.Paste")
			(net "GND")
		)
		(pad "68" smd rect
			(at -2.050034 -6.374892 270)
			(size 0.519938 1.4986)
			(layers "F.Cu" "F.Mask" "F.Paste")
			(net "M_F_CPU0_SA_CA<2>")
		)
		(pad "69" smd rect
			(at -2.050034 -5.525008 270)
			(size 0.519938 1.4986)
			(layers "F.Cu" "F.Mask" "F.Paste")
			(net "GND")
		)
		(pad "70" smd rect
			(at -2.050034 -4.675124 270)
			(size 0.519938 1.4986)
			(layers "F.Cu" "F.Mask" "F.Paste")
			(net "M_F_CPU0_SA_CA<4>")
		)
		(pad "71" smd rect
			(at -2.050034 -3.824986 270)
			(size 0.519938 1.4986)
			(layers "F.Cu" "F.Mask" "F.Paste")
			(net "GND")
		)
		(pad "72" smd rect
			(at -2.050034 -2.975102 270)
			(size 0.519938 1.4986)
			(layers "F.Cu" "F.Mask" "F.Paste")
			(net "M_F_CPU0_SA_CA<6>")
		)
		(pad "73" smd rect
			(at -2.050034 -2.124964 270)
			(size 0.519938 1.4986)
			(layers "F.Cu" "F.Mask" "F.Paste")
			(net "GND")
		)
		(pad "74" smd rect
			(at -2.050034 -1.27508 270)
			(size 0.519938 1.4986)
			(layers "F.Cu" "F.Mask" "F.Paste")
			(net "M_F_CPU0_SA_PAR")
		)
		(pad "75" smd rect
			(at -2.050034 -0.424942 270)
			(size 0.519938 1.4986)
			(layers "F.Cu" "F.Mask" "F.Paste")
			(net "GND")
		)
		(pad "76" smd rect
			(at -2.050034 5.525008 270)
			(size 0.519938 1.4986)
			(layers "F.Cu" "F.Mask" "F.Paste")
			(net "M_F_CPU0_SB_CA<0>")
		)
		(pad "77" smd rect
			(at -2.050034 6.374892 270)
			(size 0.519938 1.4986)
			(layers "F.Cu" "F.Mask" "F.Paste")
			(net "GND")
		)
		(pad "78" smd rect
			(at -2.050034 7.22503 270)
			(size 0.519938 1.4986)
			(layers "F.Cu" "F.Mask" "F.Paste")
			(net "M_F_CPU0_SB_CA<2>")
		)
		(pad "79" smd rect
			(at -2.050034 8.074914 270)
			(size 0.519938 1.4986)
			(layers "F.Cu" "F.Mask" "F.Paste")
			(net "GND")
		)
		(pad "80" smd rect
			(at -2.050034 8.925052 270)
			(size 0.519938 1.4986)
			(layers "F.Cu" "F.Mask" "F.Paste")
			(net "M_F_CPU0_SB_CA<4>")
		)
		(pad "81" smd rect
			(at -2.050034 9.774936 270)
			(size 0.519938 1.4986)
			(layers "F.Cu" "F.Mask" "F.Paste")
			(net "GND")
		)
		(pad "82" smd rect
			(at -2.050034 10.625074 270)
			(size 0.519938 1.4986)
			(layers "F.Cu" "F.Mask" "F.Paste")
			(net "M_F_CPU0_SB_CA<6>")
		)
		(pad "83" smd rect
			(at -2.050034 11.474958 270)
			(size 0.519938 1.4986)
			(layers "F.Cu" "F.Mask" "F.Paste")
			(net "GND")
		)
		(pad "84" smd rect
			(at -2.050034 12.325096 270)
			(size 0.519938 1.4986)
			(layers "F.Cu" "F.Mask" "F.Paste")
			(net "M_F_CPU0_SB_CS_N<2>")
		)
		(pad "85" smd rect
			(at -2.050034 13.17498 270)
			(size 0.519938 1.4986)
			(layers "F.Cu" "F.Mask" "F.Paste")
			(net "GND")
		)
		(pad "86" smd rect
			(at -2.050034 14.025118 270)
			(size 0.519938 1.4986)
			(layers "F.Cu" "F.Mask" "F.Paste")
			(net "M_F_CPU0_SA_RSP<1>")
		)
		(pad "87" smd rect
			(at -2.050034 14.875002 270)
			(size 0.519938 1.4986)
			(layers "F.Cu" "F.Mask" "F.Paste")
			(net "M_F_CPU0_SB_RSP<1>")
		)
		(pad "88" smd rect
			(at -2.050034 15.724886 270)
			(size 0.519938 1.4986)
			(layers "F.Cu" "F.Mask" "F.Paste")
			(net "GND")
		)
		(pad "89" smd rect
			(at -2.050034 16.575024 270)
			(size 0.519938 1.4986)
			(layers "F.Cu" "F.Mask" "F.Paste")
			(net "M_F_CPU0_SB_CB<4>")
		)
		(pad "90" smd rect
			(at -2.050034 17.424908 270)
			(size 0.519938 1.4986)
			(layers "F.Cu" "F.Mask" "F.Paste")
			(net "GND")
		)
		(pad "91" smd rect
			(at -2.050034 18.275046 270)
			(size 0.519938 1.4986)
			(layers "F.Cu" "F.Mask" "F.Paste")
			(net "M_F_CPU0_SB_CB<5>")
		)
	)
)
